(kicad_pcb
	(version 20260206)
	(generator "pcbnew")
	(generator_version "10.0")
	(general
		(thickness 1.6)
		(legacy_teardrops no)
	)
	(paper "A4")
	(title_block
		(title "01162023_DA0F0TEBIF0_F0T_Expander_BD_F_brd_V02_OCP.brd")
		(comment 1 "Grand Teton / footprint 3799 of 9728 (J20), pads 1-109 of 179")
	)
	(layers
		(0 "F.Cu" signal "TOP")
		(4 "In1.Cu" signal "GND")
		(6 "In2.Cu" signal "VCC")
		(8 "In3.Cu" signal "VCC1")
		(10 "In4.Cu" signal "GND1")
		(12 "In5.Cu" signal "IN1")
		(14 "In6.Cu" signal "GND2")
		(16 "In7.Cu" signal "IN2")
		(18 "In8.Cu" signal "GND3")
		(20 "In9.Cu" signal "IN3")
		(22 "In10.Cu" signal "GND4")
		(24 "In11.Cu" signal "IN4")
		(26 "In12.Cu" signal "GND5")
		(28 "In13.Cu" signal "IN5")
		(30 "In14.Cu" signal "GND6")
		(32 "In15.Cu" signal "IN6")
		(34 "In16.Cu" signal "GND7")
		(2 "B.Cu" signal "BOTTOM")
		(9 "F.Adhes" user "F.Adhesive")
		(11 "B.Adhes" user "B.Adhesive")
		(13 "F.Paste" user "Package Geometry/Pastemask Top")
		(15 "B.Paste" user "Package Geometry/Pastemask Bottom")
		(5 "F.SilkS" user "Ref Des/Silkscreen Top")
		(7 "B.SilkS" user "Ref Des/Silkscreen Bottom")
		(1 "F.Mask" user "Board Geometry/Soldermask Top")
		(3 "B.Mask" user "Board Geometry/Soldermask Bottom")
		(17 "Dwgs.User" user "User.Drawings")
		(19 "Cmts.User" user "User.Comments")
		(21 "Eco1.User" user "User.Eco1")
		(23 "Eco2.User" user "User.Eco2")
		(25 "Edge.Cuts" user "Board Geometry/Outline")
		(27 "Margin" user)
		(31 "F.CrtYd" user "Package Geometry/Place Bound Top")
		(29 "B.CrtYd" user "Package Geometry/Place Bound Bottom")
		(35 "F.Fab" user "Ref Des/Assembly Top")
		(33 "B.Fab" user "Ref Des/Assembly Bottom")
	)
	(footprint ""
		(layer "F.Cu")
		(at 47.319946 -127.700024)
		(property "Reference" "J20"
			(at -5.307076 34.685224 90)
			(unlocked yes)
			(layer "F.SilkS")
			(effects
				(font
					(size 0.7874 0.5842)
					(thickness 0.1524)
				)
				(justify left)
			)
		)
		(property "Value" ""
			(at 0 0 0)
			(layer "F.Fab")
			(effects
				(font
					(size 1.27 1.27)
				)
			)
		)
		(duplicate_pad_numbers_are_jumpers no)
		(pad "" np_thru_hole circle
			(at -0.727456 -32.485076)
			(size 1.1176 1.1176)
			(drill 1.1176)
			(layers "*.Cu" "*.Mask")
			(clearance 0.381)
			(thermal_gap 0.381)
		)
		(pad "" np_thru_hole circle
			(at 1.022604 32.485076)
			(size 1.1176 1.1176)
			(drill 1.1176)
			(layers "*.Cu" "*.Mask")
			(clearance 0.381)
			(thermal_gap 0.381)
		)
		(pad "A1" smd rect
			(at 3.322574 -18.465038 270)
			(size 0.3556 1.2192)
			(layers "F.Cu" "F.Mask" "F.Paste")
			(net "GND")
		)
		(pad "A2" smd rect
			(at 3.322574 -17.86509 270)
			(size 0.3556 1.2192)
			(layers "F.Cu" "F.Mask" "F.Paste")
			(net "GND")
		)
		(pad "A3" smd rect
			(at 3.322574 -17.264888 270)
			(size 0.3556 1.2192)
			(layers "F.Cu" "F.Mask" "F.Paste")
			(net "GND")
		)
		(pad "A4" smd rect
			(at 3.322574 -16.66494 270)
			(size 0.3556 1.2192)
			(layers "F.Cu" "F.Mask" "F.Paste")
			(net "GND")
		)
		(pad "A5" smd rect
			(at 3.322574 -16.064992 270)
			(size 0.3556 1.2192)
			(layers "F.Cu" "F.Mask" "F.Paste")
			(net "GND")
		)
		(pad "A6" smd rect
			(at 3.322574 -15.465044 270)
			(size 0.3556 1.2192)
			(layers "F.Cu" "F.Mask" "F.Paste")
			(net "GND")
		)
		(pad "A7" smd rect
			(at 3.322574 -14.865096 270)
			(size 0.3556 1.2192)
			(layers "F.Cu" "F.Mask" "F.Paste")
			(net "SMB_NIC0_R_SCL")
		)
		(pad "A8" smd rect
			(at 3.322574 -14.264894 270)
			(size 0.3556 1.2192)
			(layers "F.Cu" "F.Mask" "F.Paste")
			(net "SMB_NIC0_R_SDA")
		)
		(pad "A9" smd rect
			(at 3.322574 -13.664946 270)
			(size 0.3556 1.2192)
			(layers "F.Cu" "F.Mask" "F.Paste")
			(net "RST_SMB_NIC0_MUX_ISO_R_N")
		)
		(pad "A10" smd rect
			(at 3.322574 -13.064998 270)
			(size 0.3556 1.2192)
			(layers "F.Cu" "F.Mask" "F.Paste")
			(net "GND")
		)
		(pad "A11" smd rect
			(at 3.322574 -12.46505 270)
			(size 0.3556 1.2192)
			(layers "F.Cu" "F.Mask" "F.Paste")
			(net "RST_NIC0_PERST1_R_N")
		)
		(pad "A12" smd rect
			(at 3.322574 -11.865102 270)
			(size 0.3556 1.2192)
			(layers "F.Cu" "F.Mask" "F.Paste")
			(net "PRSNTB2_NIC0_N")
		)
		(pad "A13" smd rect
			(at 3.322574 -11.2649 270)
			(size 0.3556 1.2192)
			(layers "F.Cu" "F.Mask" "F.Paste")
			(net "GND")
		)
		(pad "A14" smd rect
			(at 3.322574 -10.664952 270)
			(size 0.3556 1.2192)
			(layers "F.Cu" "F.Mask" "F.Paste")
			(net "Net_2575")
		)
		(pad "A15" smd rect
			(at 3.322574 -10.065004 270)
			(size 0.3556 1.2192)
			(layers "F.Cu" "F.Mask" "F.Paste")
			(net "Net_2578")
		)
		(pad "A16" smd rect
			(at 3.322574 -9.465056 270)
			(size 0.3556 1.2192)
			(layers "F.Cu" "F.Mask" "F.Paste")
			(net "GND")
		)
		(pad "A17" smd rect
			(at 3.322574 -8.865108 270)
			(size 0.3556 1.2192)
			(layers "F.Cu" "F.Mask" "F.Paste")
			(net "P5E_PEX0_STN1_RX_DN<31>")
		)
		(pad "A18" smd rect
			(at 3.322574 -8.264906 270)
			(size 0.3556 1.2192)
			(layers "F.Cu" "F.Mask" "F.Paste")
			(net "P5E_PEX0_STN1_RX_DP<31>")
		)
		(pad "A19" smd rect
			(at 3.322574 -7.664958 270)
			(size 0.3556 1.2192)
			(layers "F.Cu" "F.Mask" "F.Paste")
			(net "GND")
		)
		(pad "A20" smd rect
			(at 3.322574 -7.06501 270)
			(size 0.3556 1.2192)
			(layers "F.Cu" "F.Mask" "F.Paste")
			(net "P5E_PEX0_STN1_RX_DN<30>")
		)
		(pad "A21" smd rect
			(at 3.322574 -6.465062 270)
			(size 0.3556 1.2192)
			(layers "F.Cu" "F.Mask" "F.Paste")
			(net "P5E_PEX0_STN1_RX_DP<30>")
		)
		(pad "A22" smd rect
			(at 3.322574 -5.865114 270)
			(size 0.3556 1.2192)
			(layers "F.Cu" "F.Mask" "F.Paste")
			(net "GND")
		)
		(pad "A23" smd rect
			(at 3.322574 -5.264912 270)
			(size 0.3556 1.2192)
			(layers "F.Cu" "F.Mask" "F.Paste")
			(net "P5E_PEX0_STN1_RX_DN<29>")
		)
		(pad "A24" smd rect
			(at 3.322574 -4.664964 270)
			(size 0.3556 1.2192)
			(layers "F.Cu" "F.Mask" "F.Paste")
			(net "P5E_PEX0_STN1_RX_DP<29>")
		)
		(pad "A25" smd rect
			(at 3.322574 -4.065016 270)
			(size 0.3556 1.2192)
			(layers "F.Cu" "F.Mask" "F.Paste")
			(net "GND")
		)
		(pad "A26" smd rect
			(at 3.322574 -3.465068 270)
			(size 0.3556 1.2192)
			(layers "F.Cu" "F.Mask" "F.Paste")
			(net "P5E_PEX0_STN1_RX_DN<28>")
		)
		(pad "A27" smd rect
			(at 3.322574 -2.86512 270)
			(size 0.3556 1.2192)
			(layers "F.Cu" "F.Mask" "F.Paste")
			(net "P5E_PEX0_STN1_RX_DP<28>")
		)
		(pad "A28" smd rect
			(at 3.322574 -2.264918 270)
			(size 0.3556 1.2192)
			(layers "F.Cu" "F.Mask" "F.Paste")
			(net "GND")
		)
		(pad "A29" smd rect
			(at 3.322574 1.74498 270)
			(size 0.3556 1.2192)
			(layers "F.Cu" "F.Mask" "F.Paste")
			(net "GND")
		)
		(pad "A30" smd rect
			(at 3.322574 2.344928 270)
			(size 0.3556 1.2192)
			(layers "F.Cu" "F.Mask" "F.Paste")
			(net "P5E_PEX0_STN1_RX_DN<27>")
		)
		(pad "A31" smd rect
			(at 3.322574 2.944876 270)
			(size 0.3556 1.2192)
			(layers "F.Cu" "F.Mask" "F.Paste")
			(net "P5E_PEX0_STN1_RX_DP<27>")
		)
		(pad "A32" smd rect
			(at 3.322574 3.545078 270)
			(size 0.3556 1.2192)
			(layers "F.Cu" "F.Mask" "F.Paste")
			(net "GND")
		)
		(pad "A33" smd rect
			(at 3.322574 4.145026 270)
			(size 0.3556 1.2192)
			(layers "F.Cu" "F.Mask" "F.Paste")
			(net "P5E_PEX0_STN1_RX_DN<26>")
		)
		(pad "A34" smd rect
			(at 3.322574 4.744974 270)
			(size 0.3556 1.2192)
			(layers "F.Cu" "F.Mask" "F.Paste")
			(net "P5E_PEX0_STN1_RX_DP<26>")
		)
		(pad "A35" smd rect
			(at 3.322574 5.344922 270)
			(size 0.3556 1.2192)
			(layers "F.Cu" "F.Mask" "F.Paste")
			(net "GND")
		)
		(pad "A36" smd rect
			(at 3.322574 5.945124 270)
			(size 0.3556 1.2192)
			(layers "F.Cu" "F.Mask" "F.Paste")
			(net "P5E_PEX0_STN1_RX_DN<25>")
		)
		(pad "A37" smd rect
			(at 3.322574 6.545072 270)
			(size 0.3556 1.2192)
			(layers "F.Cu" "F.Mask" "F.Paste")
			(net "P5E_PEX0_STN1_RX_DP<25>")
		)
		(pad "A38" smd rect
			(at 3.322574 7.14502 270)
			(size 0.3556 1.2192)
			(layers "F.Cu" "F.Mask" "F.Paste")
			(net "GND")
		)
		(pad "A39" smd rect
			(at 3.322574 7.744968 270)
			(size 0.3556 1.2192)
			(layers "F.Cu" "F.Mask" "F.Paste")
			(net "P5E_PEX0_STN1_RX_DN<24>")
		)
		(pad "A40" smd rect
			(at 3.322574 8.344916 270)
			(size 0.3556 1.2192)
			(layers "F.Cu" "F.Mask" "F.Paste")
			(net "P5E_PEX0_STN1_RX_DP<24>")
		)
		(pad "A41" smd rect
			(at 3.322574 8.945118 270)
			(size 0.3556 1.2192)
			(layers "F.Cu" "F.Mask" "F.Paste")
			(net "GND")
		)
		(pad "A42" smd rect
			(at 3.322574 9.545066 270)
			(size 0.3556 1.2192)
			(layers "F.Cu" "F.Mask" "F.Paste")
			(net "PRSNTB1_NIC0_N")
		)
		(pad "A43" smd rect
			(at 3.322574 14.454886 270)
			(size 0.3556 1.2192)
			(layers "F.Cu" "F.Mask" "F.Paste")
			(net "GND")
		)
		(pad "A44" smd rect
			(at 3.322574 15.055088 270)
			(size 0.3556 1.2192)
			(layers "F.Cu" "F.Mask" "F.Paste")
			(net "P5E_PEX0_STN1_RX_DN<23>")
		)
		(pad "A45" smd rect
			(at 3.322574 15.655036 270)
			(size 0.3556 1.2192)
			(layers "F.Cu" "F.Mask" "F.Paste")
			(net "P5E_PEX0_STN1_RX_DP<23>")
		)
		(pad "A46" smd rect
			(at 3.322574 16.254984 270)
			(size 0.3556 1.2192)
			(layers "F.Cu" "F.Mask" "F.Paste")
			(net "GND")
		)
		(pad "A47" smd rect
			(at 3.322574 16.854932 270)
			(size 0.3556 1.2192)
			(layers "F.Cu" "F.Mask" "F.Paste")
			(net "P5E_PEX0_STN1_RX_DN<22>")
		)
		(pad "A48" smd rect
			(at 3.322574 17.45488 270)
			(size 0.3556 1.2192)
			(layers "F.Cu" "F.Mask" "F.Paste")
			(net "P5E_PEX0_STN1_RX_DP<22>")
		)
		(pad "A49" smd rect
			(at 3.322574 18.055082 270)
			(size 0.3556 1.2192)
			(layers "F.Cu" "F.Mask" "F.Paste")
			(net "GND")
		)
		(pad "A50" smd rect
			(at 3.322574 18.65503 270)
			(size 0.3556 1.2192)
			(layers "F.Cu" "F.Mask" "F.Paste")
			(net "P5E_PEX0_STN1_RX_DN<21>")
		)
		(pad "A51" smd rect
			(at 3.322574 19.254978 270)
			(size 0.3556 1.2192)
			(layers "F.Cu" "F.Mask" "F.Paste")
			(net "P5E_PEX0_STN1_RX_DP<21>")
		)
		(pad "A52" smd rect
			(at 3.322574 19.854926 270)
			(size 0.3556 1.2192)
			(layers "F.Cu" "F.Mask" "F.Paste")
			(net "GND")
		)
		(pad "A53" smd rect
			(at 3.322574 20.455128 270)
			(size 0.3556 1.2192)
			(layers "F.Cu" "F.Mask" "F.Paste")
			(net "P5E_PEX0_STN1_RX_DN<20>")
		)
		(pad "A54" smd rect
			(at 3.322574 21.055076 270)
			(size 0.3556 1.2192)
			(layers "F.Cu" "F.Mask" "F.Paste")
			(net "P5E_PEX0_STN1_RX_DP<20>")
		)
		(pad "A55" smd rect
			(at 3.322574 21.655024 270)
			(size 0.3556 1.2192)
			(layers "F.Cu" "F.Mask" "F.Paste")
			(net "GND")
		)
		(pad "A56" smd rect
			(at 3.322574 22.254972 270)
			(size 0.3556 1.2192)
			(layers "F.Cu" "F.Mask" "F.Paste")
			(net "P5E_PEX0_STN1_RX_DN<19>")
		)
		(pad "A57" smd rect
			(at 3.322574 22.85492 270)
			(size 0.3556 1.2192)
			(layers "F.Cu" "F.Mask" "F.Paste")
			(net "P5E_PEX0_STN1_RX_DP<19>")
		)
		(pad "A58" smd rect
			(at 3.322574 23.455122 270)
			(size 0.3556 1.2192)
			(layers "F.Cu" "F.Mask" "F.Paste")
			(net "GND")
		)
		(pad "A59" smd rect
			(at 3.322574 24.05507 270)
			(size 0.3556 1.2192)
			(layers "F.Cu" "F.Mask" "F.Paste")
			(net "P5E_PEX0_STN1_RX_DN<18>")
		)
		(pad "A60" smd rect
			(at 3.322574 24.655018 270)
			(size 0.3556 1.2192)
			(layers "F.Cu" "F.Mask" "F.Paste")
			(net "P5E_PEX0_STN1_RX_DP<18>")
		)
		(pad "A61" smd rect
			(at 3.322574 25.254966 270)
			(size 0.3556 1.2192)
			(layers "F.Cu" "F.Mask" "F.Paste")
			(net "GND")
		)
		(pad "A62" smd rect
			(at 3.322574 25.854914 270)
			(size 0.3556 1.2192)
			(layers "F.Cu" "F.Mask" "F.Paste")
			(net "P5E_PEX0_STN1_RX_DN<17>")
		)
		(pad "A63" smd rect
			(at 3.322574 26.455116 270)
			(size 0.3556 1.2192)
			(layers "F.Cu" "F.Mask" "F.Paste")
			(net "P5E_PEX0_STN1_RX_DP<17>")
		)
		(pad "A64" smd rect
			(at 3.322574 27.055064 270)
			(size 0.3556 1.2192)
			(layers "F.Cu" "F.Mask" "F.Paste")
			(net "GND")
		)
		(pad "A65" smd rect
			(at 3.322574 27.655012 270)
			(size 0.3556 1.2192)
			(layers "F.Cu" "F.Mask" "F.Paste")
			(net "P5E_PEX0_STN1_RX_DN<16>")
		)
		(pad "A66" smd rect
			(at 3.322574 28.25496 270)
			(size 0.3556 1.2192)
			(layers "F.Cu" "F.Mask" "F.Paste")
			(net "P5E_PEX0_STN1_RX_DP<16>")
		)
		(pad "A67" smd rect
			(at 3.322574 28.854908 270)
			(size 0.3556 1.2192)
			(layers "F.Cu" "F.Mask" "F.Paste")
			(net "GND")
		)
		(pad "A68" smd rect
			(at 3.322574 29.45511 270)
			(size 0.3556 1.2192)
			(layers "F.Cu" "F.Mask" "F.Paste")
			(net "Net_2583")
		)
		(pad "A69" smd rect
			(at 3.322574 30.055058 270)
			(size 0.3556 1.2192)
			(layers "F.Cu" "F.Mask" "F.Paste")
			(net "Net_2584")
		)
		(pad "A70" smd rect
			(at 3.322574 30.655006 270)
			(size 0.3556 1.2192)
			(layers "F.Cu" "F.Mask" "F.Paste")
			(net "NIC0_PWRBRK_R_N")
		)
		(pad "B1" smd rect
			(at -1.27762 -18.465038 270)
			(size 0.3556 1.2192)
			(layers "F.Cu" "F.Mask" "F.Paste")
			(net "P12V_NIC0")
		)
		(pad "B2" smd rect
			(at -1.27762 -17.86509 270)
			(size 0.3556 1.2192)
			(layers "F.Cu" "F.Mask" "F.Paste")
			(net "P12V_NIC0")
		)
		(pad "B3" smd rect
			(at -1.27762 -17.264888 270)
			(size 0.3556 1.2192)
			(layers "F.Cu" "F.Mask" "F.Paste")
			(net "P12V_NIC0")
		)
		(pad "B4" smd rect
			(at -1.27762 -16.66494 270)
			(size 0.3556 1.2192)
			(layers "F.Cu" "F.Mask" "F.Paste")
			(net "P12V_NIC0")
		)
		(pad "B5" smd rect
			(at -1.27762 -16.064992 270)
			(size 0.3556 1.2192)
			(layers "F.Cu" "F.Mask" "F.Paste")
			(net "P12V_NIC0")
		)
		(pad "B6" smd rect
			(at -1.27762 -15.465044 270)
			(size 0.3556 1.2192)
			(layers "F.Cu" "F.Mask" "F.Paste")
			(net "P12V_NIC0")
		)
		(pad "B7" smd rect
			(at -1.27762 -14.865096 270)
			(size 0.3556 1.2192)
			(layers "F.Cu" "F.Mask" "F.Paste")
			(net "NIC0_BIF0_N")
		)
		(pad "B8" smd rect
			(at -1.27762 -14.264894 270)
			(size 0.3556 1.2192)
			(layers "F.Cu" "F.Mask" "F.Paste")
			(net "NIC0_BIF1_N")
		)
		(pad "B9" smd rect
			(at -1.27762 -13.664946 270)
			(size 0.3556 1.2192)
			(layers "F.Cu" "F.Mask" "F.Paste")
			(net "NIC0_BIF2_N")
		)
		(pad "B10" smd rect
			(at -1.27762 -13.064998 270)
			(size 0.3556 1.2192)
			(layers "F.Cu" "F.Mask" "F.Paste")
			(net "RST_NIC0_PERST0_R_N")
		)
		(pad "B11" smd rect
			(at -1.27762 -12.46505 270)
			(size 0.3556 1.2192)
			(layers "F.Cu" "F.Mask" "F.Paste")
			(net "P3V3_NIC0")
		)
		(pad "B12" smd rect
			(at -1.27762 -11.865102 270)
			(size 0.3556 1.2192)
			(layers "F.Cu" "F.Mask" "F.Paste")
			(net "NIC0_AUX_PWR_EN_R")
		)
		(pad "B13" smd rect
			(at -1.27762 -11.2649 270)
			(size 0.3556 1.2192)
			(layers "F.Cu" "F.Mask" "F.Paste")
			(net "GND")
		)
		(pad "B14" smd rect
			(at -1.27762 -10.664952 270)
			(size 0.3556 1.2192)
			(layers "F.Cu" "F.Mask" "F.Paste")
			(net "CLK_100M_DB2000QL_NIC0_R_DN")
		)
		(pad "B15" smd rect
			(at -1.27762 -10.065004 270)
			(size 0.3556 1.2192)
			(layers "F.Cu" "F.Mask" "F.Paste")
			(net "CLK_100M_DB2000QL_NIC0_R_DP")
		)
		(pad "B16" smd rect
			(at -1.27762 -9.465056 270)
			(size 0.3556 1.2192)
			(layers "F.Cu" "F.Mask" "F.Paste")
			(net "GND")
		)
		(pad "B17" smd rect
			(at -1.27762 -8.865108 270)
			(size 0.3556 1.2192)
			(layers "F.Cu" "F.Mask" "F.Paste")
			(net "P5E_PEX0_STN1_TX_C_DP<31>")
		)
		(pad "B18" smd rect
			(at -1.27762 -8.264906 270)
			(size 0.3556 1.2192)
			(layers "F.Cu" "F.Mask" "F.Paste")
			(net "P5E_PEX0_STN1_TX_C_DN<31>")
		)
		(pad "B19" smd rect
			(at -1.27762 -7.664958 270)
			(size 0.3556 1.2192)
			(layers "F.Cu" "F.Mask" "F.Paste")
			(net "GND")
		)
		(pad "B20" smd rect
			(at -1.27762 -7.06501 270)
			(size 0.3556 1.2192)
			(layers "F.Cu" "F.Mask" "F.Paste")
			(net "P5E_PEX0_STN1_TX_C_DN<30>")
		)
		(pad "B21" smd rect
			(at -1.27762 -6.465062 270)
			(size 0.3556 1.2192)
			(layers "F.Cu" "F.Mask" "F.Paste")
			(net "P5E_PEX0_STN1_TX_C_DP<30>")
		)
		(pad "B22" smd rect
			(at -1.27762 -5.865114 270)
			(size 0.3556 1.2192)
			(layers "F.Cu" "F.Mask" "F.Paste")
			(net "GND")
		)
		(pad "B23" smd rect
			(at -1.27762 -5.264912 270)
			(size 0.3556 1.2192)
			(layers "F.Cu" "F.Mask" "F.Paste")
			(net "P5E_PEX0_STN1_TX_C_DP<29>")
		)
		(pad "B24" smd rect
			(at -1.27762 -4.664964 270)
			(size 0.3556 1.2192)
			(layers "F.Cu" "F.Mask" "F.Paste")
			(net "P5E_PEX0_STN1_TX_C_DN<29>")
		)
		(pad "B25" smd rect
			(at -1.27762 -4.065016 270)
			(size 0.3556 1.2192)
			(layers "F.Cu" "F.Mask" "F.Paste")
			(net "GND")
		)
		(pad "B26" smd rect
			(at -1.27762 -3.465068 270)
			(size 0.3556 1.2192)
			(layers "F.Cu" "F.Mask" "F.Paste")
			(net "P5E_PEX0_STN1_TX_C_DN<28>")
		)
		(pad "B27" smd rect
			(at -1.27762 -2.86512 270)
			(size 0.3556 1.2192)
			(layers "F.Cu" "F.Mask" "F.Paste")
			(net "P5E_PEX0_STN1_TX_C_DP<28>")
		)
		(pad "B28" smd rect
			(at -1.27762 -2.264918 270)
			(size 0.3556 1.2192)
			(layers "F.Cu" "F.Mask" "F.Paste")
			(net "GND")
		)
		(pad "B29" smd rect
			(at -1.27762 1.74498 270)
			(size 0.3556 1.2192)
			(layers "F.Cu" "F.Mask" "F.Paste")
			(net "GND")
		)
		(pad "B30" smd rect
			(at -1.27762 2.344928 270)
			(size 0.3556 1.2192)
			(layers "F.Cu" "F.Mask" "F.Paste")
			(net "P5E_PEX0_STN1_TX_C_DP<27>")
		)
		(pad "B31" smd rect
			(at -1.27762 2.944876 270)
			(size 0.3556 1.2192)
			(layers "F.Cu" "F.Mask" "F.Paste")
			(net "P5E_PEX0_STN1_TX_C_DN<27>")
		)
		(pad "B32" smd rect
			(at -1.27762 3.545078 270)
			(size 0.3556 1.2192)
			(layers "F.Cu" "F.Mask" "F.Paste")
			(net "GND")
		)
		(pad "B33" smd rect
			(at -1.27762 4.145026 270)
			(size 0.3556 1.2192)
			(layers "F.Cu" "F.Mask" "F.Paste")
			(net "P5E_PEX0_STN1_TX_C_DN<26>")
		)
		(pad "B34" smd rect
			(at -1.27762 4.744974 270)
			(size 0.3556 1.2192)
			(layers "F.Cu" "F.Mask" "F.Paste")
			(net "P5E_PEX0_STN1_TX_C_DP<26>")
		)
		(pad "B35" smd rect
			(at -1.27762 5.344922 270)
			(size 0.3556 1.2192)
			(layers "F.Cu" "F.Mask" "F.Paste")
			(net "GND")
		)
		(pad "B36" smd rect
			(at -1.27762 5.945124 270)
			(size 0.3556 1.2192)
			(layers "F.Cu" "F.Mask" "F.Paste")
			(net "P5E_PEX0_STN1_TX_C_DP<25>")
		)
		(pad "B37" smd rect
			(at -1.27762 6.545072 270)
			(size 0.3556 1.2192)
			(layers "F.Cu" "F.Mask" "F.Paste")
			(net "P5E_PEX0_STN1_TX_C_DN<25>")
		)
	)
)
